FILE_TYPE = CONNECTIVITY;
{Allegro Design Entry HDL 17.4-2019 S026 (4007227) 1/17/2022}
"PAGE_NUMBER" = 213;
0"NC";
END.
